# S9S_MB_2U (Grand Teton) — schematic netlist excerpt (pin names and nets, part order shuffled) for the footprints in the layout excerpt that follows; sources: Cadence DE-HDL packaged netlist, KiCad conversion of 03242023_DA0F0TMBIJ0_F0T_Motherboard_J_brd_V01_OCP.brd

PC443_P1_2  Q_CAP  3300PF 50V 10% X7R  pkg 0402  page 293 : A = SW_P12V_PVCCINFAON_CPU1_FLT ; B = GND
C2275  Q_CAP  0.1UF 25V 10% X7R  pkg 0402  page 170 : A = P3V3_AUX ; B = GND

(kicad_pcb
	(version 20260206)
	(generator "pcbnew")
	(generator_version "10.0")
	(general
		(thickness 1.6)
		(legacy_teardrops no)
	)
	(paper "A4")
	(title_block
		(title "03242023_DA0F0TMBIJ0_F0T_Motherboard_J_brd_V01_OCP.brd")
		(comment 1 "Grand Teton / footprints 786-787 of 6105")
	)
	(layers
		(0 "F.Cu" signal "TOP")
		(4 "In1.Cu" signal "GND")
		(6 "In2.Cu" signal "IN1")
		(8 "In3.Cu" signal "GND1")
		(10 "In4.Cu" signal "IN2")
		(12 "In5.Cu" signal "GND2")
		(14 "In6.Cu" signal "IN3")
		(16 "In7.Cu" signal "GND3")
		(18 "In8.Cu" signal "VCC")
		(20 "In9.Cu" signal "VCC1")
		(22 "In10.Cu" signal "GND4")
		(24 "In11.Cu" signal "IN4")
		(26 "In12.Cu" signal "GND5")
		(28 "In13.Cu" signal "IN5")
		(30 "In14.Cu" signal "GND6")
		(32 "In15.Cu" signal "IN6")
		(34 "In16.Cu" signal "GND7")
		(2 "B.Cu" signal "BOTTOM")
		(9 "F.Adhes" user "F.Adhesive")
		(11 "B.Adhes" user "B.Adhesive")
		(13 "F.Paste" user "Package Geometry/Pastemask Top")
		(15 "B.Paste" user "Package Geometry/Pastemask Bottom")
		(5 "F.SilkS" user "Ref Des/Silkscreen Top")
		(7 "B.SilkS" user "Ref Des/Silkscreen Bottom")
		(1 "F.Mask" user "Board Geometry/Soldermask Top")
		(3 "B.Mask" user "Board Geometry/Soldermask Bottom")
		(17 "Dwgs.User" user "User.Drawings")
		(19 "Cmts.User" user "User.Comments")
		(21 "Eco1.User" user "User.Eco1")
		(23 "Eco2.User" user "User.Eco2")
		(25 "Edge.Cuts" user "Board Geometry/Outline")
		(27 "Margin" user)
		(31 "F.CrtYd" user "Package Geometry/Place Bound Top")
		(29 "B.CrtYd" user "Package Geometry/Place Bound Bottom")
		(35 "F.Fab" user "Ref Des/Assembly Top")
		(33 "B.Fab" user "Ref Des/Assembly Bottom")
	)
	(footprint ""
		(layer "F.Cu")
		(at 50.785014 -152.164542 90)
		(property "Reference" "PC443_P1_2"
			(at 0 0 90)
			(layer "F.SilkS")
			(hide yes)
			(effects
				(font
					(size 1.27 1.27)
				)
			)
		)
		(property "Value" ""
			(at 0 0 90)
			(layer "F.Fab")
			(effects
				(font
					(size 1.27 1.27)
				)
			)
		)
		(duplicate_pad_numbers_are_jumpers no)
		(fp_line
			(start 0.7874 -0.4064)
			(end 0.7874 0.4064)
			(stroke
				(width 0.1524)
				(type default)
			)
			(layer "F.SilkS")
		)
		(fp_line
			(start -0.7874 -0.4064)
			(end 0.7874 -0.4064)
			(stroke
				(width 0.1524)
				(type default)
			)
			(layer "F.SilkS")
		)
		(fp_line
			(start 0.7874 0.4064)
			(end -0.7874 0.4064)
			(stroke
				(width 0.1524)
				(type default)
			)
			(layer "F.SilkS")
		)
		(fp_line
			(start -0.7874 0.4064)
			(end -0.7874 -0.4064)
			(stroke
				(width 0.1524)
				(type default)
			)
			(layer "F.SilkS")
		)
		(fp_line
			(start -0.12065 -0.305054)
			(end -0.12065 -0.2794)
			(stroke
				(width 0.1)
				(type default)
			)
			(layer "F.Fab")
		)
		(fp_line
			(start -0.67945 -0.305054)
			(end -0.12065 -0.305054)
			(stroke
				(width 0.1)
				(type default)
			)
			(layer "F.Fab")
		)
		(fp_line
			(start 0.67945 -0.3048)
			(end 0.67945 0.3048)
			(stroke
				(width 0.1)
				(type default)
			)
			(layer "F.Fab")
		)
		(fp_line
			(start 0.12065 -0.3048)
			(end 0.67945 -0.3048)
			(stroke
				(width 0.1)
				(type default)
			)
			(layer "F.Fab")
		)
		(fp_line
			(start 0.12065 -0.2794)
			(end 0.12065 -0.3048)
			(stroke
				(width 0.1)
				(type default)
			)
			(layer "F.Fab")
		)
		(fp_line
			(start -0.12065 -0.2794)
			(end 0.12065 -0.2794)
			(stroke
				(width 0.1)
				(type default)
			)
			(layer "F.Fab")
		)
		(fp_line
			(start 0.120396 0.2794)
			(end -0.12065 0.2794)
			(stroke
				(width 0.1)
				(type default)
			)
			(layer "F.Fab")
		)
		(fp_line
			(start -0.12065 0.2794)
			(end -0.12065 0.3048)
			(stroke
				(width 0.1)
				(type default)
			)
			(layer "F.Fab")
		)
		(fp_line
			(start 0.67945 0.3048)
			(end 0.120396 0.3048)
			(stroke
				(width 0.1)
				(type default)
			)
			(layer "F.Fab")
		)
		(fp_line
			(start 0.120396 0.3048)
			(end 0.120396 0.2794)
			(stroke
				(width 0.1)
				(type default)
			)
			(layer "F.Fab")
		)
		(fp_line
			(start -0.12065 0.3048)
			(end -0.67945 0.3048)
			(stroke
				(width 0.1)
				(type default)
			)
			(layer "F.Fab")
		)
		(fp_line
			(start -0.67945 0.3048)
			(end -0.67945 -0.305054)
			(stroke
				(width 0.1)
				(type default)
			)
			(layer "F.Fab")
		)
		(pad "1" smd circle
			(at -0.40005 0 90)
			(size 0 0)
			(layers "F.Cu" "F.Mask" "F.Paste")
			(net "SW_P12V_PVCCINFAON_CPU1_FLT")
		)
		(pad "2" smd circle
			(at 0.40005 0 90)
			(size 0 0)
			(layers "F.Cu" "F.Mask" "F.Paste")
			(net "GND")
		)
	)
	(footprint ""
		(layer "F.Cu")
		(at 103.519478 -420.84879 90)
		(property "Reference" "C2275"
			(at 0 0 90)
			(layer "F.SilkS")
			(hide yes)
			(effects
				(font
					(size 1.27 1.27)
				)
			)
		)
		(property "Value" ""
			(at 0 0 90)
			(layer "F.Fab")
			(effects
				(font
					(size 1.27 1.27)
				)
			)
		)
		(duplicate_pad_numbers_are_jumpers no)
		(fp_line
			(start 0.7874 -0.4064)
			(end 0.7874 0.4064)
			(stroke
				(width 0.1524)
				(type default)
			)
			(layer "F.SilkS")
		)
		(fp_line
			(start -0.7874 -0.4064)
			(end 0.7874 -0.4064)
			(stroke
				(width 0.1524)
				(type default)
			)
			(layer "F.SilkS")
		)
		(fp_line
			(start 0.7874 0.4064)
			(end -0.7874 0.4064)
			(stroke
				(width 0.1524)
				(type default)
			)
			(layer "F.SilkS")
		)
		(fp_line
			(start -0.7874 0.4064)
			(end -0.7874 -0.4064)
			(stroke
				(width 0.1524)
				(type default)
			)
			(layer "F.SilkS")
		)
		(fp_line
			(start -0.12065 -0.305054)
			(end -0.12065 -0.2794)
			(stroke
				(width 0.1)
				(type default)
			)
			(layer "F.Fab")
		)
		(fp_line
			(start -0.67945 -0.305054)
			(end -0.12065 -0.305054)
			(stroke
				(width 0.1)
				(type default)
			)
			(layer "F.Fab")
		)
		(fp_line
			(start 0.67945 -0.3048)
			(end 0.67945 0.3048)
			(stroke
				(width 0.1)
				(type default)
			)
			(layer "F.Fab")
		)
		(fp_line
			(start 0.12065 -0.3048)
			(end 0.67945 -0.3048)
			(stroke
				(width 0.1)
				(type default)
			)
			(layer "F.Fab")
		)
		(fp_line
			(start 0.12065 -0.2794)
			(end 0.12065 -0.3048)
			(stroke
				(width 0.1)
				(type default)
			)
			(layer "F.Fab")
		)
		(fp_line
			(start -0.12065 -0.2794)
			(end 0.12065 -0.2794)
			(stroke
				(width 0.1)
				(type default)
			)
			(layer "F.Fab")
		)
		(fp_line
			(start 0.120396 0.2794)
			(end -0.12065 0.2794)
			(stroke
				(width 0.1)
				(type default)
			)
			(layer "F.Fab")
		)
		(fp_line
			(start -0.12065 0.2794)
			(end -0.12065 0.3048)
			(stroke
				(width 0.1)
				(type default)
			)
			(layer "F.Fab")
		)
		(fp_line
			(start 0.67945 0.3048)
			(end 0.120396 0.3048)
			(stroke
				(width 0.1)
				(type default)
			)
			(layer "F.Fab")
		)
		(fp_line
			(start 0.120396 0.3048)
			(end 0.120396 0.2794)
			(stroke
				(width 0.1)
				(type default)
			)
			(layer "F.Fab")
		)
		(fp_line
			(start -0.12065 0.3048)
			(end -0.67945 0.3048)
			(stroke
				(width 0.1)
				(type default)
			)
			(layer "F.Fab")
		)
		(fp_line
			(start -0.67945 0.3048)
			(end -0.67945 -0.305054)
			(stroke
				(width 0.1)
				(type default)
			)
			(layer "F.Fab")
		)
		(pad "1" smd circle
			(at -0.40005 0 90)
			(size 0 0)
			(layers "F.Cu" "F.Mask" "F.Paste")
			(net "P3V3_AUX")
		)
		(pad "2" smd circle
			(at 0.40005 0 90)
			(size 0 0)
			(layers "F.Cu" "F.Mask" "F.Paste")
			(net "GND")
		)
	)
)
